#ISCELL
  mstr_symbols bom_note *
  *
#ISCELL
  mstr_symbols intel_corp_bpage *
  *
#ISCELL
  mstr_standard offpage *
  page79_i1
#ISCELL
  mstr_standard tap *
  page79_i10
#ISCELL
  mstr_standard tap *
  page79_i100
#ISCELL
  mstr_standard tap *
  page79_i101
#ISCELL
  mstr_standard tap *
  page79_i102
#ISCELL
  mstr_standard tap *
  page79_i103
#ISCELL
  mstr_standard tap *
  page79_i104
#ISCELL
  mstr_standard tap *
  page79_i105
#ISCELL
  mstr_standard tap *
  page79_i106
#ISCELL
  mstr_standard tap *
  page79_i107
#ISCELL
  mstr_standard tap *
  page79_i108
#ISCELL
  mstr_standard tap *
  page79_i109
#ISCELL
  mstr_standard tap *
  page79_i11
#ISCELL
  mstr_standard tap *
  page79_i110
#CELL
  mstr_sconn sconn288_h44441004 *
  page79_i111
#ISCELL
  mstr_standard tap *
  page79_i112
#ISCELL
  mstr_standard tap *
  page79_i113
#ISCELL
  mstr_standard tap *
  page79_i114
#ISCELL
  mstr_standard tap *
  page79_i115
#ISCELL
  mstr_standard tap *
  page79_i116
#ISCELL
  mstr_standard tap *
  page79_i117
#ISCELL
  mstr_standard tap *
  page79_i118
#ISCELL
  mstr_standard tap *
  page79_i119
#ISCELL
  mstr_standard tap *
  page79_i12
#ISCELL
  mstr_standard tap *
  page79_i120
#ISCELL
  mstr_standard tap *
  page79_i121
#ISCELL
  mstr_standard tap *
  page79_i122
#ISCELL
  mstr_standard tap *
  page79_i123
#ISCELL
  mstr_standard tap *
  page79_i124
#ISCELL
  mstr_standard tap *
  page79_i125
#ISCELL
  mstr_standard tap *
  page79_i126
#ISCELL
  mstr_standard tap *
  page79_i127
#ISCELL
  mstr_standard tap *
  page79_i128
#ISCELL
  mstr_standard tap *
  page79_i129
#ISCELL
  mstr_standard tap *
  page79_i13
#ISCELL
  mstr_standard offpage *
  page79_i130
#ISCELL
  mstr_standard tap *
  page79_i131
#ISCELL
  mstr_standard tap *
  page79_i132
#ISCELL
  mstr_standard tap *
  page79_i133
#ISCELL
  mstr_standard tap *
  page79_i134
#ISCELL
  mstr_standard offpage *
  page79_i135
#ISCELL
  mstr_standard offpage *
  page79_i136
#ISCELL
  mstr_standard offpage *
  page79_i137
#ISCELL
  mstr_standard tap *
  page79_i138
#ISCELL
  mstr_standard tap *
  page79_i139
#ISCELL
  mstr_symbols pvddq_ghj *
  page79_i14
#ISCELL
  mstr_standard tap *
  page79_i140
#ISCELL
  mstr_standard tap *
  page79_i141
#ISCELL
  mstr_standard tap *
  page79_i142
#ISCELL
  mstr_standard tap *
  page79_i143
#ISCELL
  mstr_standard tap *
  page79_i144
#ISCELL
  mstr_standard tap *
  page79_i145
#ISCELL
  mstr_standard offpage *
  page79_i146
#ISCELL
  mstr_standard offpage *
  page79_i147
#ISCELL
  mstr_standard offpage *
  page79_i148
#ISCELL
  mstr_standard offpage *
  page79_i149
#ISCELL
  mstr_standard offpage *
  page79_i150
#ISCELL
  mstr_standard tap *
  page79_i152
#ISCELL
  mstr_standard tap *
  page79_i153
#ISCELL
  mstr_standard tap *
  page79_i154
#ISCELL
  mstr_standard tap *
  page79_i155
#ISCELL
  mstr_standard offpage *
  page79_i156
#ISCELL
  mstr_standard offpage *
  page79_i157
#ISCELL
  mstr_standard tap *
  page79_i158
#ISCELL
  mstr_standard tap *
  page79_i159
#ISCELL
  mstr_symbols pvtt_ghj *
  page79_i16
#ISCELL
  mstr_standard tap *
  page79_i160
#ISCELL
  mstr_standard tap *
  page79_i161
#ISCELL
  mstr_standard tap *
  page79_i162
#ISCELL
  mstr_standard tap *
  page79_i163
#ISCELL
  mstr_standard tap *
  page79_i164
#ISCELL
  mstr_standard offpage *
  page79_i165
#ISCELL
  mstr_standard offpage *
  page79_i166
#ISCELL
  mstr_standard offpage *
  page79_i167
#ISCELL
  mstr_standard tap *
  page79_i168
#CELL
  mstr_sconn sconn288_h44441004 *
  page79_i169
#ISCELL
  mstr_standard tap *
  page79_i17
#ISCELL
  mstr_symbols gnd *
  page79_i170
#ISCELL
  mstr_standard offpage *
  page79_i171
#ISCELL
  mstr_standard offpage *
  page79_i172
#ISCELL
  mstr_standard offpage *
  page79_i173
#ISCELL
  mstr_symbols gnd *
  page79_i175
#ISCELL
  mstr_standard offpage *
  page79_i176
#ISCELL
  mstr_symbols gnd *
  page79_i177
#CELL
  dev_discrete cap_a *
  page79_i178
#ISCELL
  mstr_symbols pvpp_ghj *
  page79_i179
#ISCELL
  mstr_standard tap *
  page79_i18
#ISCELL
  mstr_symbols pvpp_ghj *
  page79_i180
#ISCELL
  mstr_standard offpage *
  page79_i181
#ISCELL
  mstr_standard tap *
  page79_i185
#ISCELL
  mstr_symbols p12v_nvdimm_ghj *
  page79_i186
#ISCELL
  mstr_standard tap *
  page79_i19
#ISCELL
  mstr_standard offpage *
  page79_i2
#ISCELL
  mstr_standard tap *
  page79_i20
#ISCELL
  mstr_standard tap *
  page79_i21
#ISCELL
  mstr_standard tap *
  page79_i22
#ISCELL
  mstr_standard tap *
  page79_i23
#ISCELL
  mstr_standard tap *
  page79_i24
#ISCELL
  mstr_standard tap *
  page79_i25
#ISCELL
  mstr_standard tap *
  page79_i26
#ISCELL
  mstr_standard tap *
  page79_i27
#ISCELL
  mstr_standard tap *
  page79_i28
#ISCELL
  mstr_standard tap *
  page79_i29
#ISCELL
  mstr_standard tap *
  page79_i3
#ISCELL
  mstr_standard tap *
  page79_i30
#ISCELL
  mstr_standard tap *
  page79_i31
#ISCELL
  mstr_standard tap *
  page79_i32
#ISCELL
  mstr_standard tap *
  page79_i33
#ISCELL
  mstr_standard tap *
  page79_i34
#ISCELL
  mstr_standard tap *
  page79_i35
#ISCELL
  mstr_standard tap *
  page79_i36
#ISCELL
  mstr_standard tap *
  page79_i37
#ISCELL
  mstr_standard tap *
  page79_i38
#ISCELL
  mstr_standard tap *
  page79_i39
#ISCELL
  mstr_standard tap *
  page79_i4
#ISCELL
  mstr_standard tap *
  page79_i40
#CELL
  mstr_sconn sconn288_h44441004 *
  page79_i43
#ISCELL
  mstr_symbols gnd *
  page79_i44
#ISCELL
  mstr_standard offpage *
  page79_i45
#ISCELL
  mstr_standard tap *
  page79_i46
#ISCELL
  mstr_standard tap *
  page79_i47
#ISCELL
  mstr_standard tap *
  page79_i48
#ISCELL
  mstr_standard tap *
  page79_i49
#ISCELL
  mstr_standard tap *
  page79_i5
#ISCELL
  mstr_standard tap *
  page79_i50
#ISCELL
  mstr_standard tap *
  page79_i51
#ISCELL
  mstr_standard tap *
  page79_i52
#ISCELL
  mstr_standard tap *
  page79_i53
#ISCELL
  mstr_standard tap *
  page79_i54
#ISCELL
  mstr_standard tap *
  page79_i55
#ISCELL
  mstr_standard tap *
  page79_i56
#ISCELL
  mstr_standard tap *
  page79_i57
#ISCELL
  mstr_standard tap *
  page79_i58
#ISCELL
  mstr_standard tap *
  page79_i59
#ISCELL
  mstr_standard tap *
  page79_i6
#ISCELL
  mstr_standard tap *
  page79_i60
#ISCELL
  mstr_standard tap *
  page79_i61
#ISCELL
  mstr_standard tap *
  page79_i62
#ISCELL
  mstr_standard tap *
  page79_i63
#CELL
  mstr_sconn sconn288_h44441004 *
  page79_i64
#ISCELL
  mstr_standard tap *
  page79_i65
#ISCELL
  mstr_standard tap *
  page79_i66
#ISCELL
  mstr_standard tap *
  page79_i67
#ISCELL
  mstr_standard tap *
  page79_i68
#ISCELL
  mstr_standard tap *
  page79_i69
#ISCELL
  mstr_standard tap *
  page79_i7
#ISCELL
  mstr_standard tap *
  page79_i70
#ISCELL
  mstr_standard tap *
  page79_i71
#ISCELL
  mstr_standard tap *
  page79_i72
#ISCELL
  mstr_standard tap *
  page79_i73
#ISCELL
  mstr_standard tap *
  page79_i74
#ISCELL
  mstr_standard tap *
  page79_i75
#ISCELL
  mstr_standard tap *
  page79_i76
#ISCELL
  mstr_standard tap *
  page79_i77
#ISCELL
  mstr_standard tap *
  page79_i78
#ISCELL
  mstr_standard tap *
  page79_i79
#ISCELL
  mstr_standard tap *
  page79_i8
#ISCELL
  mstr_standard tap *
  page79_i80
#ISCELL
  mstr_standard tap *
  page79_i81
#ISCELL
  mstr_standard tap *
  page79_i82
#ISCELL
  mstr_standard tap *
  page79_i83
#ISCELL
  mstr_standard tap *
  page79_i84
#ISCELL
  mstr_standard tap *
  page79_i85
#ISCELL
  mstr_standard tap *
  page79_i86
#ISCELL
  mstr_standard tap *
  page79_i87
#ISCELL
  mstr_standard tap *
  page79_i88
#ISCELL
  mstr_standard tap *
  page79_i89
#ISCELL
  mstr_standard tap *
  page79_i9
#ISCELL
  mstr_standard tap *
  page79_i90
#ISCELL
  mstr_standard tap *
  page79_i91
#ISCELL
  mstr_standard tap *
  page79_i92
#ISCELL
  mstr_standard tap *
  page79_i93
#ISCELL
  mstr_standard tap *
  page79_i94
#ISCELL
  mstr_standard tap *
  page79_i95
#ISCELL
  mstr_standard tap *
  page79_i96
#ISCELL
  mstr_standard tap *
  page79_i97
#ISCELL
  mstr_standard tap *
  page79_i98
#ISCELL
  mstr_standard tap *
  page79_i99
